(kicad_pcb
	(version 20241229)
	(generator "pcbnew")
	(generator_version "9.0")
	(general
		(thickness 1.6296)
		(legacy_teardrops no)
	)
	(paper "A3")
	(title_block
		(title "Thunderbolt to 10GbE adapter")
		(date "2026-04-21")
		(rev "1.1.0")
		(company "Antmicro Ltd")
		(comment 1 "www.antmicro.com")
		(comment 9 "footprints 653-657 of 703")
	)
	(layers
		(0 "F.Cu" signal)
		(4 "In1.Cu" signal)
		(6 "In2.Cu" signal)
		(8 "In3.Cu" signal)
		(10 "In4.Cu" signal)
		(12 "In5.Cu" signal)
		(14 "In6.Cu" signal)
		(2 "B.Cu" signal)
		(9 "F.Adhes" user "F.Adhesive")
		(11 "B.Adhes" user "B.Adhesive")
		(13 "F.Paste" user)
		(15 "B.Paste" user)
		(5 "F.SilkS" user "F.Silkscreen")
		(7 "B.SilkS" user "B.Silkscreen")
		(1 "F.Mask" user)
		(3 "B.Mask" user)
		(17 "Dwgs.User" user "User.Drawings")
		(19 "Cmts.User" user "User.Comments")
		(21 "Eco1.User" user "User.Eco1")
		(23 "Eco2.User" user "User.Eco2")
		(25 "Edge.Cuts" user)
		(27 "Margin" user)
		(31 "F.CrtYd" user "F.Courtyard")
		(29 "B.CrtYd" user "B.Courtyard")
		(35 "F.Fab" user)
		(33 "B.Fab" user)
	)
	(footprint "antmicro-footprints:C_0402_1005Metric"
		(layer "B.Cu")
		(at 128.009997 117.629999 180)
		(descr "Capacitor SMD 0402")
		(tags "capacitor SMD 0402")
		(property "Reference" "C92"
			(at -21.900002 7.700002 0)
			(layer "B.SilkS")
			(effects
				(font
					(size 0.7 0.7)
					(thickness 0.15)
				)
				(justify mirror)
			)
		)
		(property "Value" "C_1u_0402"
			(at -1.022927 -2.155213 0)
			(layer "B.Fab")
			(effects
				(font
					(size 0.7 0.7)
					(thickness 0.15)
				)
				(justify left bottom mirror)
			)
		)
		(property "Datasheet" "https://product.tdk.com/en/search/capacitor/ceramic/mlcc/info?part_no=C1005X6S1A105K050BC"
			(at 0 0 0)
			(layer "B.Fab")
			(hide yes)
			(effects
				(font
					(size 1.27 1.27)
					(thickness 0.15)
				)
				(justify mirror)
			)
		)
		(property "Description" "SMD Multilayer Ceramic Capacitor, 1 µF, 10 V, 0402 [1005 Metric], ± 10%, X6S, C"
			(at 0 0 0)
			(layer "B.Fab")
			(hide yes)
			(effects
				(font
					(size 1.27 1.27)
					(thickness 0.15)
				)
				(justify mirror)
			)
		)
		(property "MPN" "C1005X6S1A105K050BC"
			(at 0 0 180)
			(unlocked yes)
			(layer "B.Fab")
			(hide yes)
			(effects
				(font
					(size 1 1)
					(thickness 0.15)
				)
				(justify mirror)
			)
		)
		(property "Manufacturer" "TDK"
			(at 0 0 180)
			(unlocked yes)
			(layer "B.Fab")
			(hide yes)
			(effects
				(font
					(size 1 1)
					(thickness 0.15)
				)
				(justify mirror)
			)
		)
		(property "License" "Apache-2.0"
			(at 0 0 180)
			(unlocked yes)
			(layer "B.Fab")
			(hide yes)
			(effects
				(font
					(size 1 1)
					(thickness 0.15)
				)
				(justify mirror)
			)
		)
		(property "Val" "1u"
			(at 0 0 180)
			(unlocked yes)
			(layer "B.Fab")
			(hide yes)
			(effects
				(font
					(size 1 1)
					(thickness 0.15)
				)
				(justify mirror)
			)
		)
		(property "Voltage" ""
			(at 0 0 180)
			(unlocked yes)
			(layer "B.Fab")
			(hide yes)
			(effects
				(font
					(size 1 1)
					(thickness 0.15)
				)
				(justify mirror)
			)
		)
		(property "Dielectric" ""
			(at 0 0 180)
			(unlocked yes)
			(layer "B.Fab")
			(hide yes)
			(effects
				(font
					(size 1 1)
					(thickness 0.15)
				)
				(justify mirror)
			)
		)
		(property "Author" "Antmicro"
			(at 0 0 180)
			(unlocked yes)
			(layer "B.Fab")
			(hide yes)
			(effects
				(font
					(size 1 1)
					(thickness 0.15)
				)
				(justify mirror)
			)
		)
		(sheetname "/TB Controller - Power/")
		(sheetfile "tb-power.kicad_sch")
		(attr smd)
		(fp_rect
			(start -0.925 0.47)
			(end 0.925 -0.47)
			(stroke
				(width 0.05)
				(type default)
			)
			(fill no)
			(layer "B.CrtYd")
		)
		(fp_line
			(start 0.504 0.25)
			(end 0.504 -0.248)
			(stroke
				(width 0.15)
				(type solid)
			)
			(layer "B.Fab")
		)
		(fp_line
			(start 0.504 -0.248)
			(end -0.494 -0.248)
			(stroke
				(width 0.15)
				(type solid)
			)
			(layer "B.Fab")
		)
		(fp_line
			(start -0.494 0.25)
			(end 0.504 0.25)
			(stroke
				(width 0.15)
				(type solid)
			)
			(layer "B.Fab")
		)
		(fp_line
			(start -0.494 -0.248)
			(end -0.494 0.25)
			(stroke
				(width 0.15)
				(type solid)
			)
			(layer "B.Fab")
		)
		(fp_text user "${REFERENCE}"
			(at -0.939 -4.599 0)
			(layer "B.Fab")
			(effects
				(font
					(size 0.7 0.7)
					(thickness 0.15)
				)
				(justify left bottom mirror)
			)
		)
		(fp_text user "License: Apache-2.0"
			(at -0.939 -5.799 0)
			(layer "B.Fab")
			(effects
				(font
					(size 0.7 0.7)
					(thickness 0.15)
				)
				(justify left bottom mirror)
			)
		)
		(fp_text user "Author: Antmicro"
			(at -0.939 -3.399 0)
			(layer "B.Fab")
			(effects
				(font
					(size 0.7 0.7)
					(thickness 0.15)
				)
				(justify left bottom mirror)
			)
		)
		(pad "1" smd roundrect
			(at -0.48 0 180)
			(size 0.59 0.64)
			(layers "B.Cu" "B.Mask" "B.Paste")
			(roundrect_rratio 0.25)
			(net 23 "GND")
			(pintype "passive")
		)
		(pad "2" smd roundrect
			(at 0.48 0 180)
			(size 0.59 0.64)
			(layers "B.Cu" "B.Mask" "B.Paste")
			(roundrect_rratio 0.25)
			(net 181 "Net-(U4A-VCC3P3_S0)")
			(pintype "passive")
		)
	)
	(footprint "antmicro-footprints:C_0402_1005Metric"
		(layer "B.Cu")
		(at 158.926866 83.085117)
		(descr "Capacitor SMD 0402")
		(tags "capacitor SMD 0402")
		(property "Reference" "C188"
			(at 19.873134 9.464883 180)
			(layer "B.SilkS")
			(effects
				(font
					(size 0.7 0.7)
					(thickness 0.15)
				)
				(justify mirror)
			)
		)
		(property "Value" "C_1u_25V_0402"
			(at -1.022927 -2.155213 180)
			(layer "B.Fab")
			(effects
				(font
					(size 0.7 0.7)
					(thickness 0.15)
				)
				(justify left bottom mirror)
			)
		)
		(property "Datasheet" "https://www.murata.com/products/productdetail?partno=GRM155R61E105KE11%23"
			(at 0 0 180)
			(layer "B.Fab")
			(hide yes)
			(effects
				(font
					(size 1.27 1.27)
					(thickness 0.15)
				)
				(justify mirror)
			)
		)
		(property "Description" "SMD Multilayer Ceramic Capacitor, 1 µF, 25 V, 0402 [1005 Metric], ± 10%, X5R, GRM Series"
			(at 0 0 180)
			(layer "B.Fab")
			(hide yes)
			(effects
				(font
					(size 1.27 1.27)
					(thickness 0.15)
				)
				(justify mirror)
			)
		)
		(property "MPN" "GRM155R61E105KE11J"
			(at 0 0 0)
			(unlocked yes)
			(layer "B.Fab")
			(hide yes)
			(effects
				(font
					(size 1 1)
					(thickness 0.15)
				)
				(justify mirror)
			)
		)
		(property "Manufacturer" "Murata"
			(at 0 0 0)
			(unlocked yes)
			(layer "B.Fab")
			(hide yes)
			(effects
				(font
					(size 1 1)
					(thickness 0.15)
				)
				(justify mirror)
			)
		)
		(property "License" "Apache-2.0"
			(at 0 0 0)
			(unlocked yes)
			(layer "B.Fab")
			(hide yes)
			(effects
				(font
					(size 1 1)
					(thickness 0.15)
				)
				(justify mirror)
			)
		)
		(property "Author" "Antmicro"
			(at 0 0 0)
			(unlocked yes)
			(layer "B.Fab")
			(hide yes)
			(effects
				(font
					(size 1 1)
					(thickness 0.15)
				)
				(justify mirror)
			)
		)
		(property "Val" "1u"
			(at 0 0 0)
			(unlocked yes)
			(layer "B.Fab")
			(hide yes)
			(effects
				(font
					(size 1 1)
					(thickness 0.15)
				)
				(justify mirror)
			)
		)
		(property "Voltage" "25V"
			(at 0 0 0)
			(unlocked yes)
			(layer "B.Fab")
			(hide yes)
			(effects
				(font
					(size 1 1)
					(thickness 0.15)
				)
				(justify mirror)
			)
		)
		(property "Dielectric" "X5R"
			(at 0 0 0)
			(unlocked yes)
			(layer "B.Fab")
			(hide yes)
			(effects
				(font
					(size 1 1)
					(thickness 0.15)
				)
				(justify mirror)
			)
		)
		(sheetname "/X710-AT2 power/")
		(sheetfile "x710-at2-power.kicad_sch")
		(attr smd)
		(fp_rect
			(start -0.925 0.47)
			(end 0.925 -0.47)
			(stroke
				(width 0.05)
				(type default)
			)
			(fill no)
			(layer "B.CrtYd")
		)
		(fp_line
			(start -0.494 -0.248)
			(end -0.494 0.25)
			(stroke
				(width 0.15)
				(type solid)
			)
			(layer "B.Fab")
		)
		(fp_line
			(start -0.494 0.25)
			(end 0.504 0.25)
			(stroke
				(width 0.15)
				(type solid)
			)
			(layer "B.Fab")
		)
		(fp_line
			(start 0.504 -0.248)
			(end -0.494 -0.248)
			(stroke
				(width 0.15)
				(type solid)
			)
			(layer "B.Fab")
		)
		(fp_line
			(start 0.504 0.25)
			(end 0.504 -0.248)
			(stroke
				(width 0.15)
				(type solid)
			)
			(layer "B.Fab")
		)
		(fp_text user "Author: Antmicro"
			(at -0.939 -3.399 180)
			(layer "B.Fab")
			(effects
				(font
					(size 0.7 0.7)
					(thickness 0.15)
				)
				(justify left bottom mirror)
			)
		)
		(fp_text user "${REFERENCE}"
			(at -0.939 -4.599 180)
			(layer "B.Fab")
			(effects
				(font
					(size 0.7 0.7)
					(thickness 0.15)
				)
				(justify left bottom mirror)
			)
		)
		(fp_text user "License: Apache-2.0"
			(at -0.939 -5.799 180)
			(layer "B.Fab")
			(effects
				(font
					(size 0.7 0.7)
					(thickness 0.15)
				)
				(justify left bottom mirror)
			)
		)
		(pad "1" smd roundrect
			(at -0.48 0)
			(size 0.59 0.64)
			(layers "B.Cu" "B.Mask" "B.Paste")
			(roundrect_rratio 0.25)
			(net 23 "GND")
			(pintype "passive")
		)
		(pad "2" smd roundrect
			(at 0.48 0)
			(size 0.59 0.64)
			(layers "B.Cu" "B.Mask" "B.Paste")
			(roundrect_rratio 0.25)
			(net 14 "P1_AVDDL")
			(pintype "passive")
		)
	)
	(footprint "antmicro-footprints:R_0402_1005Metric"
		(layer "B.Cu")
		(at 161.981866 69.5 90)
		(descr "Resistor SMD 0402")
		(tags "resistor SMD 0402")
		(property "Reference" "R176"
			(at -2.25 0 270)
			(layer "B.SilkS")
			(effects
				(font
					(size 0.7 0.7)
					(thickness 0.15)
				)
				(justify mirror)
			)
		)
		(property "Value" "R_1k_0402"
			(at -1.011843 -1.772047 270)
			(layer "B.Fab")
			(effects
				(font
					(size 0.7 0.7)
					(thickness 0.15)
				)
				(justify left bottom mirror)
			)
		)
		(property "Datasheet" "https://www.bourns.com/docs/product-datasheets/cr.pdf"
			(at 0 0 270)
			(layer "B.Fab")
			(hide yes)
			(effects
				(font
					(size 1.27 1.27)
					(thickness 0.15)
				)
				(justify mirror)
			)
		)
		(property "Description" "SMD Chip Resistor, 1 kohm, ± 1%, 63 mW, 0402 [1005 Metric], Thick Film, General Purpose"
			(at 0 0 270)
			(layer "B.Fab")
			(hide yes)
			(effects
				(font
					(size 1.27 1.27)
					(thickness 0.15)
				)
				(justify mirror)
			)
		)
		(property "MPN" "CR0402-FX-1001GLF"
			(at 0 0 90)
			(unlocked yes)
			(layer "B.Fab")
			(hide yes)
			(effects
				(font
					(size 1 1)
					(thickness 0.15)
				)
				(justify mirror)
			)
		)
		(property "Manufacturer" "Bourns"
			(at 0 0 90)
			(unlocked yes)
			(layer "B.Fab")
			(hide yes)
			(effects
				(font
					(size 1 1)
					(thickness 0.15)
				)
				(justify mirror)
			)
		)
		(property "License" "Apache-2.0"
			(at 0 0 90)
			(unlocked yes)
			(layer "B.Fab")
			(hide yes)
			(effects
				(font
					(size 1 1)
					(thickness 0.15)
				)
				(justify mirror)
			)
		)
		(property "Author" "Antmicro"
			(at 0 0 90)
			(unlocked yes)
			(layer "B.Fab")
			(hide yes)
			(effects
				(font
					(size 1 1)
					(thickness 0.15)
				)
				(justify mirror)
			)
		)
		(property "Val" "1k"
			(at 0 0 90)
			(unlocked yes)
			(layer "B.Fab")
			(hide yes)
			(effects
				(font
					(size 1 1)
					(thickness 0.15)
				)
				(justify mirror)
			)
		)
		(property "Tolerance" "1%"
			(at 0 0 90)
			(unlocked yes)
			(layer "B.Fab")
			(hide yes)
			(effects
				(font
					(size 1 1)
					(thickness 0.15)
				)
				(justify mirror)
			)
		)
		(sheetname "/X710-AT2 Misc/")
		(sheetfile "x710-at2-mics.kicad_sch")
		(attr smd)
		(fp_rect
			(start -0.925 0.47)
			(end 0.925 -0.47)
			(stroke
				(width 0.05)
				(type default)
			)
			(fill no)
			(layer "B.CrtYd")
		)
		(fp_rect
			(start -0.5 0.25)
			(end 0.5 -0.25)
			(stroke
				(width 0.15)
				(type solid)
			)
			(fill no)
			(layer "B.Fab")
		)
		(fp_text user "License: Apache-2.0"
			(at -0.95 -5.169 270)
			(layer "B.Fab")
			(effects
				(font
					(size 0.7 0.7)
					(thickness 0.15)
				)
				(justify left bottom mirror)
			)
		)
		(fp_text user "${REFERENCE}"
			(at -0.95 -3.168 270)
			(layer "B.Fab")
			(effects
				(font
					(size 0.7 0.7)
					(thickness 0.15)
				)
				(justify left bottom mirror)
			)
		)
		(fp_text user "Author: Antmicro"
			(at -0.95 -4.169 270)
			(layer "B.Fab")
			(effects
				(font
					(size 0.7 0.7)
					(thickness 0.15)
				)
				(justify left bottom mirror)
			)
		)
		(pad "1" smd roundrect
			(at -0.48 0 90)
			(size 0.59 0.64)
			(layers "B.Cu" "B.Mask" "B.Paste")
			(roundrect_rratio 0.25)
			(net 124 "/X710-AT2 10GbE/~{P1_INT}")
			(pintype "passive")
		)
		(pad "2" smd roundrect
			(at 0.48 0 90)
			(size 0.59 0.64)
			(layers "B.Cu" "B.Mask" "B.Paste")
			(roundrect_rratio 0.25)
			(net 7 "+3V3")
			(pintype "passive")
		)
	)
	(footprint "antmicro-footprints:TP_SMD_0.75mm"
		(layer "B.Cu")
		(at 157.521866 77.185117 180)
		(property "Reference" "TP33"
			(at -20.778136 -9.414883 0)
			(layer "B.SilkS")
			(effects
				(font
					(size 0.7 0.7)
					(thickness 0.15)
				)
				(justify mirror)
			)
		)
		(property "Value" "TP_0.75mm_SMD"
			(at 0 -1.2 0)
			(layer "B.Fab")
			(effects
				(font
					(size 0.7 0.7)
					(thickness 0.15)
				)
				(justify left bottom mirror)
			)
		)
		(property "Description" "SMT test point"
			(at 0 0 0)
			(layer "B.Fab")
			(hide yes)
			(effects
				(font
					(size 1.27 1.27)
					(thickness 0.15)
				)
				(justify mirror)
			)
		)
		(property "MPN" ""
			(at 0 0 180)
			(unlocked yes)
			(layer "B.Fab")
			(hide yes)
			(effects
				(font
					(size 1 1)
					(thickness 0.15)
				)
				(justify mirror)
			)
		)
		(property "Manufacturer" ""
			(at 0 0 180)
			(unlocked yes)
			(layer "B.Fab")
			(hide yes)
			(effects
				(font
					(size 1 1)
					(thickness 0.15)
				)
				(justify mirror)
			)
		)
		(property "Author" "Antmicro"
			(at 0 0 180)
			(unlocked yes)
			(layer "B.Fab")
			(hide yes)
			(effects
				(font
					(size 1 1)
					(thickness 0.15)
				)
				(justify mirror)
			)
		)
		(property "License" "Apache-2.0"
			(at 0 0 180)
			(unlocked yes)
			(layer "B.Fab")
			(hide yes)
			(effects
				(font
					(size 1 1)
					(thickness 0.15)
				)
				(justify mirror)
			)
		)
		(sheetname "/X710-AT2 Misc/")
		(sheetfile "x710-at2-mics.kicad_sch")
		(attr exclude_from_pos_files exclude_from_bom)
		(fp_circle
			(center 0 0)
			(end 0.475 0)
			(stroke
				(width 0.05)
				(type default)
			)
			(fill no)
			(layer "B.CrtYd")
		)
		(fp_text user "Author: Antmicro"
			(at -0.4 -3.901 0)
			(layer "B.Fab")
			(effects
				(font
					(size 0.7 0.7)
					(thickness 0.15)
				)
				(justify left bottom mirror)
			)
		)
		(fp_text user "License: Apache-2.0"
			(at -0.4 -5.101 0)
			(layer "B.Fab")
			(effects
				(font
					(size 0.7 0.7)
					(thickness 0.15)
				)
				(justify left bottom mirror)
			)
		)
		(fp_text user "${REFERENCE}"
			(at -0.4 -2.7 0)
			(layer "B.Fab")
			(effects
				(font
					(size 0.7 0.7)
					(thickness 0.15)
				)
				(justify left bottom mirror)
			)
		)
		(pad "1" smd circle
			(at 0 0 180)
			(size 0.75 0.75)
			(layers "B.Cu" "B.Mask")
			(net 106 "/X710-AT2 Misc/PHY_TDI")
			(pinfunction "1")
			(pintype "passive")
		)
	)
	(footprint "antmicro-footprints:C_0402_1005Metric"
		(layer "B.Cu")
		(at 127.524999 121.999999 -90)
		(descr "Capacitor SMD 0402")
		(tags "capacitor SMD 0402")
		(property "Reference" "C87"
			(at -7.700002 -21.900002 90)
			(layer "B.SilkS")
			(effects
				(font
					(size 0.7 0.7)
					(thickness 0.15)
				)
				(justify mirror)
			)
		)
		(property "Value" "C_100n_0402"
			(at -1.022927 -2.155213 90)
			(layer "B.Fab")
			(effects
				(font
					(size 0.7 0.7)
					(thickness 0.15)
				)
				(justify left bottom mirror)
			)
		)
		(property "Datasheet" "https://www.murata.com/products/productdetail?partno=GRM155R61H104KE14%23"
			(at 0 0 90)
			(layer "B.Fab")
			(hide yes)
			(effects
				(font
					(size 1.27 1.27)
					(thickness 0.15)
				)
				(justify mirror)
			)
		)
		(property "Description" "SMD Multilayer Ceramic Capacitor, 0.1 µF, 50 V, 0402 [1005 Metric], ± 10%, X5R, GRM Series"
			(at 0 0 90)
			(layer "B.Fab")
			(hide yes)
			(effects
				(font
					(size 1.27 1.27)
					(thickness 0.15)
				)
				(justify mirror)
			)
		)
		(property "MPN" "GRM155R61H104KE14D"
			(at 0 0 270)
			(unlocked yes)
			(layer "B.Fab")
			(hide yes)
			(effects
				(font
					(size 1 1)
					(thickness 0.15)
				)
				(justify mirror)
			)
		)
		(property "Manufacturer" "Murata"
			(at 0 0 270)
			(unlocked yes)
			(layer "B.Fab")
			(hide yes)
			(effects
				(font
					(size 1 1)
					(thickness 0.15)
				)
				(justify mirror)
			)
		)
		(property "License" "Apache-2.0"
			(at 0 0 270)
			(unlocked yes)
			(layer "B.Fab")
			(hide yes)
			(effects
				(font
					(size 1 1)
					(thickness 0.15)
				)
				(justify mirror)
			)
		)
		(property "Val" "100n"
			(at 0 0 270)
			(unlocked yes)
			(layer "B.Fab")
			(hide yes)
			(effects
				(font
					(size 1 1)
					(thickness 0.15)
				)
				(justify mirror)
			)
		)
		(property "Voltage" "50V"
			(at 0 0 270)
			(unlocked yes)
			(layer "B.Fab")
			(hide yes)
			(effects
				(font
					(size 1 1)
					(thickness 0.15)
				)
				(justify mirror)
			)
		)
		(property "Dielectric" "X5R"
			(at 0 0 270)
			(unlocked yes)
			(layer "B.Fab")
			(hide yes)
			(effects
				(font
					(size 1 1)
					(thickness 0.15)
				)
				(justify mirror)
			)
		)
		(property "Author" "Antmicro"
			(at 0 0 270)
			(unlocked yes)
			(layer "B.Fab")
			(hide yes)
			(effects
				(font
					(size 1 1)
					(thickness 0.15)
				)
				(justify mirror)
			)
		)
		(sheetname "/TB Controller - Power/")
		(sheetfile "tb-power.kicad_sch")
		(attr smd)
		(fp_rect
			(start -0.925 0.47)
			(end 0.925 -0.47)
			(stroke
				(width 0.05)
				(type default)
			)
			(fill no)
			(layer "B.CrtYd")
		)
		(fp_line
			(start -0.494 0.25)
			(end 0.504 0.25)
			(stroke
				(width 0.15)
				(type solid)
			)
			(layer "B.Fab")
		)
		(fp_line
			(start 0.504 0.25)
			(end 0.504 -0.248)
			(stroke
				(width 0.15)
				(type solid)
			)
			(layer "B.Fab")
		)
		(fp_line
			(start -0.494 -0.248)
			(end -0.494 0.25)
			(stroke
				(width 0.15)
				(type solid)
			)
			(layer "B.Fab")
		)
		(fp_line
			(start 0.504 -0.248)
			(end -0.494 -0.248)
			(stroke
				(width 0.15)
				(type solid)
			)
			(layer "B.Fab")
		)
		(fp_text user "Author: Antmicro"
			(at -0.939 -3.399 90)
			(layer "B.Fab")
			(effects
				(font
					(size 0.7 0.7)
					(thickness 0.15)
				)
				(justify left bottom mirror)
			)
		)
		(fp_text user "${REFERENCE}"
			(at -0.939 -4.599 90)
			(layer "B.Fab")
			(effects
				(font
					(size 0.7 0.7)
					(thickness 0.15)
				)
				(justify left bottom mirror)
			)
		)
		(fp_text user "License: Apache-2.0"
			(at -0.939 -5.799 90)
			(layer "B.Fab")
			(effects
				(font
					(size 0.7 0.7)
					(thickness 0.15)
				)
				(justify left bottom mirror)
			)
		)
		(pad "1" smd roundrect
			(at -0.48 0 270)
			(size 0.59 0.64)
			(layers "B.Cu" "B.Mask" "B.Paste")
			(roundrect_rratio 0.25)
			(net 23 "GND")
			(pintype "passive")
		)
		(pad "2" smd roundrect
			(at 0.48 0 270)
			(size 0.59 0.64)
			(layers "B.Cu" "B.Mask" "B.Paste")
			(roundrect_rratio 0.25)
			(net 181 "Net-(U4A-VCC3P3_S0)")
			(pintype "passive")
		)
	)
)
